(kicad_pcb
	(version 20260206)
	(generator "pcbnew")
	(generator_version "10.0")
	(general
		(thickness 1.6)
		(legacy_teardrops no)
	)
	(paper "A4")
	(title_block
		(title "v2-tray-backplane — ms_tbp_v2.brd")
		(comment 1 "Open CloudServer (Microsoft) / footprints 42-50 of 164")
	)
	(layers
		(0 "F.Cu" signal "TOP")
		(4 "In1.Cu" signal "LYR2")
		(6 "In2.Cu" signal "LYR3")
		(8 "In3.Cu" signal "LYR4")
		(10 "In4.Cu" signal "LYR5")
		(12 "In5.Cu" signal "LYR6")
		(14 "In6.Cu" signal "LYR7")
		(2 "B.Cu" signal "BOTTOM")
		(9 "F.Adhes" user "F.Adhesive")
		(11 "B.Adhes" user "B.Adhesive")
		(13 "F.Paste" user "Package Geometry/Pastemask Top")
		(15 "B.Paste" user "Package Geometry/Pastemask Bottom")
		(5 "F.SilkS" user "Ref Des/Silkscreen Top")
		(7 "B.SilkS" user "Ref Des/Silkscreen Bottom")
		(1 "F.Mask" user "Board Geometry/Soldermask Top")
		(3 "B.Mask" user "Board Geometry/Soldermask Bottom")
		(17 "Dwgs.User" user "User.Drawings")
		(19 "Cmts.User" user "User.Comments")
		(21 "Eco1.User" user "User.Eco1")
		(23 "Eco2.User" user "User.Eco2")
		(25 "Edge.Cuts" user "Board Geometry/Outline")
		(27 "Margin" user)
		(31 "F.CrtYd" user "Package Geometry/Place Bound Top")
		(29 "B.CrtYd" user "Package Geometry/Place Bound Bottom")
		(35 "F.Fab" user "Ref Des/Assembly Top")
		(33 "B.Fab" user "Ref Des/Assembly Bottom")
	)
	(footprint ""
		(layer "F.Cu")
		(at -199.4408 21.1074 -90)
		(property "Reference" "J27"
			(at -1.2573 -5.3848 0)
			(unlocked yes)
			(layer "F.SilkS")
			(effects
				(font
					(size 0.762 0.5334)
					(thickness 0.1016)
				)
			)
		)
		(property "Value" ""
			(at 0 0 270)
			(layer "F.Fab")
			(effects
				(font
					(size 1.27 1.27)
				)
			)
		)
		(duplicate_pad_numbers_are_jumpers no)
		(fp_line
			(start 0.499999 8.75)
			(end 0.499999 7.350001)
			(stroke
				(width 0.127)
				(type default)
			)
			(layer "F.SilkS")
		)
		(fp_line
			(start 3.7 8.75)
			(end 0.499999 8.75)
			(stroke
				(width 0.127)
				(type default)
			)
			(layer "F.SilkS")
		)
		(fp_line
			(start -2.7 7.350001)
			(end -0.700001 7.350001)
			(stroke
				(width 0.127)
				(type default)
			)
			(layer "F.SilkS")
		)
		(fp_line
			(start 3.7 7.350001)
			(end 3.7 8.75)
			(stroke
				(width 0.127)
				(type default)
			)
			(layer "F.SilkS")
		)
		(fp_line
			(start 4.9 7.350001)
			(end 6.899999 7.350001)
			(stroke
				(width 0.127)
				(type default)
			)
			(layer "F.SilkS")
		)
		(fp_line
			(start 6.899999 7.350001)
			(end 6.899999 5.349999)
			(stroke
				(width 0.127)
				(type default)
			)
			(layer "F.SilkS")
		)
		(fp_line
			(start -2.7 5.349999)
			(end -2.7 7.350001)
			(stroke
				(width 0.127)
				(type default)
			)
			(layer "F.SilkS")
		)
		(fp_line
			(start 6.899999 -0.249999)
			(end 6.899999 -2.250001)
			(stroke
				(width 0.127)
				(type default)
			)
			(layer "F.SilkS")
		)
		(fp_line
			(start -2.7 -2.250001)
			(end -2.7 -0.249999)
			(stroke
				(width 0.127)
				(type default)
			)
			(layer "F.SilkS")
		)
		(fp_line
			(start -0.700001 -2.250001)
			(end -2.7 -2.250001)
			(stroke
				(width 0.127)
				(type default)
			)
			(layer "F.SilkS")
		)
		(fp_line
			(start 6.899999 -2.250001)
			(end 4.9 -2.250001)
			(stroke
				(width 0.127)
				(type default)
			)
			(layer "F.SilkS")
		)
		(fp_poly
			(pts
				(arc
					(start 9.728799 5.1962)
					(mid 8.255565 9.269839)
					(end 4.3002 11.036201)
				)
				(arc
					(start 4.099499 11.036201)
					(mid 4.005521 11.033698)
					(end 3.9116 11.029599)
				)
				(xy 0.289999 11.029599) (xy 0.282001 11.030001) (xy 0.280101 11.030001)
				(arc
					(start 0.279999 11.0301)
					(mid 0.20252 11.033493)
					(end 0.125001 11.0358)
				)
				(arc
					(start -0.125199 11.0358)
					(mid -3.994922 9.33426)
					(end -5.536301 5.398)
				)
				(arc
					(start -5.536301 0.099799)
					(mid -3.939989 -3.890625)
					(end 0.03 -5.537101)
				)
				(xy 4.1029 -5.537101)
				(arc
					(start 4.1037 -5.536301)
					(mid 8.186368 -3.843008)
					(end 9.729099 0.2989)
				)
				(xy 9.729099 5.1959)
			)
			(stroke
				(width 0)
				(type default)
			)
			(fill no)
			(layer "B.CrtYd")
		)
		(fp_poly
			(pts
				(xy -3.200001 -2.75) (xy 7.4 -2.75) (xy 7.4 7.85) (xy -3.200001 7.85)
			)
			(stroke
				(width 0)
				(type default)
			)
			(fill no)
			(layer "F.CrtYd")
		)
		(fp_line
			(start -2.7 7.350001)
			(end -2.7 -2.250001)
			(stroke
				(width 0.1)
				(type default)
			)
			(layer "F.Fab")
		)
		(fp_line
			(start 6.899999 7.350001)
			(end -2.7 7.350001)
			(stroke
				(width 0.1)
				(type default)
			)
			(layer "F.Fab")
		)
		(fp_line
			(start -2.7 -2.250001)
			(end 6.899999 -2.250001)
			(stroke
				(width 0.1)
				(type default)
			)
			(layer "F.Fab")
		)
		(fp_line
			(start 6.899999 -2.250001)
			(end 6.899999 7.350001)
			(stroke
				(width 0.1)
				(type default)
			)
			(layer "F.Fab")
		)
		(fp_text user "3"
			(at -0.21336 8.11784 0)
			(unlocked yes)
			(layer "F.SilkS")
			(effects
				(font
					(size 0.762 0.5334)
					(thickness 0.1016)
				)
			)
		)
		(fp_text user "4"
			(at 4.42468 7.9883 0)
			(unlocked yes)
			(layer "F.SilkS")
			(effects
				(font
					(size 0.762 0.5334)
					(thickness 0.1016)
				)
			)
		)
		(fp_text user "2"
			(at 4.23164 -2.96164 0)
			(unlocked yes)
			(layer "F.SilkS")
			(effects
				(font
					(size 0.762 0.5334)
					(thickness 0.1016)
				)
			)
		)
		(fp_text user "*"
			(at 0.2286 -4.54025 270)
			(unlocked yes)
			(layer "F.SilkS")
			(effects
				(font
					(size 0.381 0.381)
					(thickness 0.381)
				)
			)
		)
		(fp_text user "3"
			(at 0 7.4071 270)
			(unlocked yes)
			(layer "B.SilkS")
			(effects
				(font
					(size 0.762 0.5334)
					(thickness 0.1016)
				)
				(justify mirror)
			)
		)
		(fp_text user "4"
			(at 4.249999 7.4071 270)
			(unlocked yes)
			(layer "B.SilkS")
			(effects
				(font
					(size 0.762 0.5334)
					(thickness 0.1016)
				)
				(justify mirror)
			)
		)
		(fp_text user "2"
			(at 4.199999 -1.867901 270)
			(unlocked yes)
			(layer "B.SilkS")
			(effects
				(font
					(size 0.762 0.5334)
					(thickness 0.1016)
				)
				(justify mirror)
			)
		)
		(fp_text user "*"
			(at 0 -1.94645 270)
			(unlocked yes)
			(layer "B.SilkS")
			(effects
				(font
					(size 0.381 0.381)
					(thickness 0.381)
				)
			)
		)
		(pad "1" thru_hole rect
			(at 0 0 270)
			(size 2.0066 2.0066)
			(drill 1.397)
			(layers "*.Cu" "*.Mask")
			(remove_unused_layers no)
			(net "P12V")
			(padstack
				(mode front_inner_back)
				(layer "Inner"
					(shape circle)
					(size 2.0066 2.0066)
				)
				(layer "B.Cu"
					(shape rect)
					(size 2.0066 2.0066)
				)
			)
		)
		(pad "2" thru_hole circle
			(at 4.199999 0 270)
			(size 2.0066 2.0066)
			(drill 1.397)
			(layers "*.Cu" "*.Mask")
			(remove_unused_layers no)
			(net "GND")
		)
		(pad "3" thru_hole circle
			(at 0 5.499999 270)
			(size 2.0066 2.0066)
			(drill 1.397)
			(layers "*.Cu" "*.Mask")
			(remove_unused_layers no)
			(net "P12V")
		)
		(pad "4" thru_hole circle
			(at 4.199999 5.499999 270)
			(size 2.0066 2.0066)
			(drill 1.397)
			(layers "*.Cu" "*.Mask")
			(remove_unused_layers no)
			(net "GND")
		)
	)
	(footprint ""
		(layer "F.Cu")
		(at -339.3694 2.794 -90)
		(property "Reference" "J26"
			(at -0.69596 3.93954 90)
			(unlocked yes)
			(layer "F.SilkS")
			(effects
				(font
					(size 0.762 0.5334)
					(thickness 0.1016)
				)
			)
		)
		(property "Value" ""
			(at 0 0 270)
			(layer "F.Fab")
			(effects
				(font
					(size 1.27 1.27)
				)
			)
		)
		(duplicate_pad_numbers_are_jumpers no)
		(fp_line
			(start -2.54 1.27)
			(end 0.127 1.27)
			(stroke
				(width 0.127)
				(type default)
			)
			(layer "F.SilkS")
		)
		(fp_line
			(start 2.443175 1.257198)
			(end 2.570175 1.257198)
			(stroke
				(width 0.127)
				(type default)
			)
			(layer "F.SilkS")
		)
		(fp_line
			(start 2.570175 1.257198)
			(end 2.570175 -1.282802)
			(stroke
				(width 0.127)
				(type default)
			)
			(layer "F.SilkS")
		)
		(fp_line
			(start -2.54 -1.27)
			(end -2.54 1.27)
			(stroke
				(width 0.127)
				(type default)
			)
			(layer "F.SilkS")
		)
		(fp_line
			(start -2.413 -1.27)
			(end -2.54 -1.27)
			(stroke
				(width 0.127)
				(type default)
			)
			(layer "F.SilkS")
		)
		(fp_line
			(start 2.570175 -1.282802)
			(end -0.096825 -1.282802)
			(stroke
				(width 0.127)
				(type default)
			)
			(layer "F.SilkS")
		)
		(fp_poly
			(pts
				(xy 0.127 3.683) (xy 0.127 1.778) (xy -3.048 1.778) (xy -3.048 -1.778) (xy -2.413 -1.778) (xy -2.413 -3.683)
				(xy -0.127 -3.683) (xy -0.127 -1.778) (xy 3.048 -1.778) (xy 3.048 1.778) (xy 2.413 1.778) (xy 2.413 3.683)
			)
			(stroke
				(width 0)
				(type default)
			)
			(fill no)
			(layer "F.CrtYd")
		)
		(fp_line
			(start -2.54 1.27)
			(end -2.54 -1.27)
			(stroke
				(width 0.1)
				(type default)
			)
			(layer "F.Fab")
		)
		(fp_line
			(start 2.54 1.27)
			(end -2.54 1.27)
			(stroke
				(width 0.1)
				(type default)
			)
			(layer "F.Fab")
		)
		(fp_line
			(start -2.54 -1.27)
			(end 2.54 -1.27)
			(stroke
				(width 0.1)
				(type default)
			)
			(layer "F.Fab")
		)
		(fp_line
			(start 2.54 -1.27)
			(end 2.54 1.27)
			(stroke
				(width 0.1)
				(type default)
			)
			(layer "F.Fab")
		)
		(fp_text user "*"
			(at -1.27 -3.89255 90)
			(unlocked yes)
			(layer "F.SilkS")
			(effects
				(font
					(size 0.381 0.381)
					(thickness 0.381)
				)
			)
		)
		(pad "1" smd rect
			(at -1.27 -1.4605 270)
			(size 1.27 3.429)
			(layers "F.Cu" "F.Mask" "F.Paste")
			(net "PSU_B1_ALERT_N")
		)
		(pad "2" smd rect
			(at 1.27 1.4605 270)
			(size 1.27 3.429)
			(layers "F.Cu" "F.Mask" "F.Paste")
			(net "UNNAMED_4_1X2HDR_I90_IO")
		)
	)
	(footprint ""
		(layer "F.Cu")
		(at -269.7226 9.0424 -90)
		(property "Reference" "C35"
			(at -0.24638 1.17856 90)
			(unlocked yes)
			(layer "F.SilkS")
			(effects
				(font
					(size 0.762 0.5334)
					(thickness 0.1016)
				)
			)
		)
		(property "Value" ""
			(at 0 0 270)
			(layer "F.Fab")
			(effects
				(font
					(size 1.27 1.27)
				)
			)
		)
		(duplicate_pad_numbers_are_jumpers no)
		(fp_line
			(start 0 -0.381)
			(end 0 0.381)
			(stroke
				(width 0.127)
				(type default)
			)
			(layer "F.SilkS")
		)
		(fp_poly
			(pts
				(xy 1.2533 0.6564) (xy -1.253299 0.6564) (xy -1.253299 -0.656399) (xy 1.2533 -0.656399)
			)
			(stroke
				(width 0)
				(type default)
			)
			(fill no)
			(layer "F.CrtYd")
		)
		(fp_line
			(start -0.762 0.381)
			(end 0.762 0.381)
			(stroke
				(width 0.1)
				(type default)
			)
			(layer "F.Fab")
		)
		(fp_line
			(start 0.762 0.381)
			(end 0.762 -0.381)
			(stroke
				(width 0.1)
				(type default)
			)
			(layer "F.Fab")
		)
		(fp_line
			(start -0.762 -0.381)
			(end -0.762 0.381)
			(stroke
				(width 0.1)
				(type default)
			)
			(layer "F.Fab")
		)
		(fp_line
			(start 0.762 -0.381)
			(end -0.762 -0.381)
			(stroke
				(width 0.1)
				(type default)
			)
			(layer "F.Fab")
		)
		(pad "1" smd rect
			(at -0.6477 0 270)
			(size 0.7112 0.8128)
			(layers "F.Cu" "F.Mask" "F.Paste")
			(net "P3V3_40G_B1_VCC_TX")
		)
		(pad "2" smd rect
			(at 0.6477 0 90)
			(size 0.7112 0.8128)
			(layers "F.Cu" "F.Mask" "F.Paste")
			(net "GND")
		)
	)
	(footprint ""
		(layer "F.Cu")
		(at -296.164 12.573 180)
		(property "Reference" "R26"
			(at -3.048 0.0889 0)
			(unlocked yes)
			(layer "F.SilkS")
			(effects
				(font
					(size 0.762 0.5334)
					(thickness 0.1016)
				)
			)
		)
		(property "Value" ""
			(at 0 0 180)
			(layer "F.Fab")
			(effects
				(font
					(size 1.27 1.27)
				)
			)
		)
		(duplicate_pad_numbers_are_jumpers no)
		(fp_line
			(start 0 -0.381)
			(end 0 0.381)
			(stroke
				(width 0.127)
				(type default)
			)
			(layer "F.SilkS")
		)
		(fp_poly
			(pts
				(xy 1.255601 0.656399) (xy -1.255601 0.656399) (xy -1.255601 -0.6564) (xy 1.255601 -0.6564)
			)
			(stroke
				(width 0)
				(type default)
			)
			(fill no)
			(layer "F.CrtYd")
		)
		(fp_line
			(start 0.800001 0.399999)
			(end 0.800001 -0.399999)
			(stroke
				(width 0.1)
				(type default)
			)
			(layer "F.Fab")
		)
		(fp_line
			(start 0.800001 -0.399999)
			(end -0.800001 -0.399999)
			(stroke
				(width 0.1)
				(type default)
			)
			(layer "F.Fab")
		)
		(fp_line
			(start -0.800001 0.399999)
			(end 0.800001 0.399999)
			(stroke
				(width 0.1)
				(type default)
			)
			(layer "F.Fab")
		)
		(fp_line
			(start -0.800001 -0.399999)
			(end -0.800001 0.399999)
			(stroke
				(width 0.1)
				(type default)
			)
			(layer "F.Fab")
		)
		(pad "1" smd rect
			(at -0.650001 0 180)
			(size 0.7112 0.8128)
			(layers "F.Cu" "F.Mask" "F.Paste")
			(net "P3V3_B1_QSFP")
		)
		(pad "2" smd rect
			(at 0.650001 0)
			(size 0.7112 0.8128)
			(layers "F.Cu" "F.Mask" "F.Paste")
			(net "ETH10G_B1_SDA")
		)
	)
	(footprint ""
		(layer "F.Cu")
		(at -46.774001 2.756002 -90)
		(property "Reference" "C20"
			(at 2.047138 0.180439 90)
			(unlocked yes)
			(layer "F.SilkS")
			(effects
				(font
					(size 0.762 0.5334)
					(thickness 0.1016)
				)
			)
		)
		(property "Value" ""
			(at 0 0 270)
			(layer "F.Fab")
			(effects
				(font
					(size 1.27 1.27)
				)
			)
		)
		(duplicate_pad_numbers_are_jumpers no)
		(fp_poly
			(pts
				(xy -0.9993 0.503999) (xy -0.9993 -0.504) (xy 0.999299 -0.504) (xy 0.999299 0.503999)
			)
			(stroke
				(width 0)
				(type default)
			)
			(fill no)
			(layer "F.CrtYd")
		)
		(fp_line
			(start -0.499999 0.249999)
			(end -0.499999 -0.25)
			(stroke
				(width 0.1)
				(type default)
			)
			(layer "F.Fab")
		)
		(fp_line
			(start 0.499999 0.249999)
			(end -0.499999 0.249999)
			(stroke
				(width 0.1)
				(type default)
			)
			(layer "F.Fab")
		)
		(fp_line
			(start -0.499999 -0.25)
			(end 0.499999 -0.25)
			(stroke
				(width 0.1)
				(type default)
			)
			(layer "F.Fab")
		)
		(fp_line
			(start 0.499999 -0.25)
			(end 0.499999 0.249999)
			(stroke
				(width 0.1)
				(type default)
			)
			(layer "F.Fab")
		)
		(pad "1" smd rect
			(at -0.4572 0)
			(size 0.508 0.5842)
			(layers "F.Cu" "F.Mask" "F.Paste")
			(net "P3V3_40G_B2_VCC_RX")
		)
		(pad "2" smd rect
			(at 0.4572 0)
			(size 0.508 0.5842)
			(layers "F.Cu" "F.Mask" "F.Paste")
			(net "GND")
		)
	)
	(footprint ""
		(layer "F.Cu")
		(at -296.164 9.779)
		(property "Reference" "R3"
			(at 2.667 -0.0889 0)
			(unlocked yes)
			(layer "F.SilkS")
			(effects
				(font
					(size 0.762 0.5334)
					(thickness 0.1016)
				)
			)
		)
		(property "Value" ""
			(at 0 0 0)
			(layer "F.Fab")
			(effects
				(font
					(size 1.27 1.27)
				)
			)
		)
		(duplicate_pad_numbers_are_jumpers no)
		(fp_line
			(start 0 -0.381)
			(end 0 0.381)
			(stroke
				(width 0.127)
				(type default)
			)
			(layer "F.SilkS")
		)
		(fp_poly
			(pts
				(xy 1.255601 0.6564) (xy -1.255601 0.6564) (xy -1.255601 -0.656399) (xy 1.255601 -0.656399)
			)
			(stroke
				(width 0)
				(type default)
			)
			(fill no)
			(layer "F.CrtYd")
		)
		(fp_line
			(start -0.800001 -0.399999)
			(end -0.800001 0.399999)
			(stroke
				(width 0.1)
				(type default)
			)
			(layer "F.Fab")
		)
		(fp_line
			(start -0.800001 0.399999)
			(end 0.800001 0.399999)
			(stroke
				(width 0.1)
				(type default)
			)
			(layer "F.Fab")
		)
		(fp_line
			(start 0.800001 -0.399999)
			(end -0.800001 -0.399999)
			(stroke
				(width 0.1)
				(type default)
			)
			(layer "F.Fab")
		)
		(fp_line
			(start 0.800001 0.399999)
			(end 0.800001 -0.399999)
			(stroke
				(width 0.1)
				(type default)
			)
			(layer "F.Fab")
		)
		(pad "1" smd rect
			(at -0.650001 0)
			(size 0.7112 0.8128)
			(layers "F.Cu" "F.Mask" "F.Paste")
			(net "SKU_B1_ID0")
		)
		(pad "2" smd rect
			(at 0.650001 0 180)
			(size 0.7112 0.8128)
			(layers "F.Cu" "F.Mask" "F.Paste")
			(net "GND")
		)
	)
	(footprint ""
		(layer "F.Cu")
		(at -281.388401 44.869202 -90)
		(property "Reference" "R17"
			(at -4.102202 -0.248501 90)
			(unlocked yes)
			(layer "F.SilkS")
			(effects
				(font
					(size 0.762 0.5334)
					(thickness 0.1016)
				)
			)
		)
		(property "Value" ""
			(at 0 0 270)
			(layer "F.Fab")
			(effects
				(font
					(size 1.27 1.27)
				)
			)
		)
		(duplicate_pad_numbers_are_jumpers no)
		(fp_line
			(start 0 -0.381)
			(end 0 0.381)
			(stroke
				(width 0.127)
				(type default)
			)
			(layer "F.SilkS")
		)
		(fp_poly
			(pts
				(xy 1.2556 0.656399) (xy -1.255601 0.656399) (xy -1.255601 -0.6564) (xy 1.2556 -0.6564)
			)
			(stroke
				(width 0)
				(type default)
			)
			(fill no)
			(layer "F.CrtYd")
		)
		(fp_line
			(start -0.800001 0.399999)
			(end 0.800001 0.399999)
			(stroke
				(width 0.1)
				(type default)
			)
			(layer "F.Fab")
		)
		(fp_line
			(start 0.800001 0.399999)
			(end 0.800001 -0.399999)
			(stroke
				(width 0.1)
				(type default)
			)
			(layer "F.Fab")
		)
		(fp_line
			(start -0.800001 -0.399999)
			(end -0.800001 0.399999)
			(stroke
				(width 0.1)
				(type default)
			)
			(layer "F.Fab")
		)
		(fp_line
			(start 0.800001 -0.399999)
			(end -0.800001 -0.399999)
			(stroke
				(width 0.1)
				(type default)
			)
			(layer "F.Fab")
		)
		(pad "1" smd rect
			(at -0.650001 0 270)
			(size 0.7112 0.8128)
			(layers "F.Cu" "F.Mask" "F.Paste")
			(net "P3V3_10G_B1_VCCT")
		)
		(pad "2" smd rect
			(at 0.650001 0 90)
			(size 0.7112 0.8128)
			(layers "F.Cu" "F.Mask" "F.Paste")
			(net "P3V3_B1_QSFP")
		)
	)
	(footprint ""
		(layer "F.Cu")
		(at -266.446 1.3716 180)
		(property "Reference" "FB9"
			(at -1.397 0.1905 0)
			(unlocked yes)
			(layer "F.SilkS")
			(effects
				(font
					(size 0.762 0.5334)
					(thickness 0.1016)
				)
				(justify left)
			)
		)
		(property "Value" ""
			(at 0 0 180)
			(layer "F.Fab")
			(effects
				(font
					(size 1.27 1.27)
				)
			)
		)
		(duplicate_pad_numbers_are_jumpers no)
		(fp_poly
			(pts
				(xy -1.016 0.508) (xy -1.016 -0.508) (xy 1.016 -0.508) (xy 1.016 0.508)
			)
			(stroke
				(width 0)
				(type default)
			)
			(fill no)
			(layer "F.CrtYd")
		)
		(fp_line
			(start 0.508 0.254)
			(end -0.508 0.254)
			(stroke
				(width 0.1)
				(type default)
			)
			(layer "F.Fab")
		)
		(fp_line
			(start 0.508 -0.254)
			(end 0.508 0.254)
			(stroke
				(width 0.1)
				(type default)
			)
			(layer "F.Fab")
		)
		(fp_line
			(start -0.508 0.254)
			(end -0.508 -0.254)
			(stroke
				(width 0.1)
				(type default)
			)
			(layer "F.Fab")
		)
		(fp_line
			(start -0.508 -0.254)
			(end 0.508 -0.254)
			(stroke
				(width 0.1)
				(type default)
			)
			(layer "F.Fab")
		)
		(pad "1" smd rect
			(at -0.4572 0 270)
			(size 0.508 0.5842)
			(layers "F.Cu" "F.Mask" "F.Paste")
			(net "UNNAMED_16_FERRITE_I40_A")
		)
		(pad "2" smd rect
			(at 0.4572 0 270)
			(size 0.508 0.5842)
			(layers "F.Cu" "F.Mask" "F.Paste")
			(net "P3V3_40G_B1_VCC_RX")
		)
	)
	(footprint ""
		(layer "F.Cu")
		(at -45.2628 6.223)
		(property "Reference" "FS5"
			(at 3.4798 0.0381 0)
			(unlocked yes)
			(layer "F.SilkS")
			(effects
				(font
					(size 0.762 0.5334)
					(thickness 0.1016)
				)
			)
		)
		(property "Value" ""
			(at 0 0 0)
			(layer "F.Fab")
			(effects
				(font
					(size 1.27 1.27)
				)
			)
		)
		(duplicate_pad_numbers_are_jumpers no)
		(fp_poly
			(pts
				(xy -1.002101 0.504) (xy -1.002101 -0.503999) (xy 1.002101 -0.503999) (xy 1.002101 0.504)
			)
			(stroke
				(width 0)
				(type default)
			)
			(fill no)
			(layer "F.CrtYd")
		)
		(fp_line
			(start -0.499999 -0.249999)
			(end -0.499999 0.25)
			(stroke
				(width 0.1)
				(type default)
			)
			(layer "F.Fab")
		)
		(fp_line
			(start -0.499999 0.25)
			(end 0.499999 0.25)
			(stroke
				(width 0.1)
				(type default)
			)
			(layer "F.Fab")
		)
		(fp_line
			(start 0.499999 -0.249999)
			(end -0.499999 -0.249999)
			(stroke
				(width 0.1)
				(type default)
			)
			(layer "F.Fab")
		)
		(fp_line
			(start 0.499999 0.25)
			(end 0.499999 -0.249999)
			(stroke
				(width 0.1)
				(type default)
			)
			(layer "F.Fab")
		)
		(pad "1" smd rect
			(at -0.459999 0 90)
			(size 0.508 0.5842)
			(layers "F.Cu" "F.Mask" "F.Paste")
			(net "P3V3_B2_QSFP")
		)
		(pad "2" smd rect
			(at 0.459999 0 90)
			(size 0.508 0.5842)
			(layers "F.Cu" "F.Mask" "F.Paste")
			(net "UNNAMED_8_FERRITE_I51_A")
		)
	)
)
